FILE_TYPE = CONNECTIVITY;
{Allegro Design Entry HDL 17.4-2019 S026 (4007227) 1/17/2022}
"PAGE_NUMBER" = 383;
0"NC";
1"P5E_CPU0_P0_RX_BUF_DP<7:0>";
2"P5E_CPU0_P0_RX_BUF_DN<7:0>";
3"P5E_CPU0_P0_RX_BUF_DN<15:8>";
4"P5E_CPU0_P0_RX_BUF_DP<15:8>";
5"P5E_CPU0_P0_RX_BUF_DN<7>";
6"P5E_CPU0_P0_RX_BUF_DN<1>";
7"P5E_CPU0_P0_RX_BUF_DN<10>";
8"P5E_CPU0_P0_RX_BUF_DN<14>";
9"P5E_CPU0_P0_RX_BUF_DN<12>";
10"P5E_CPU0_P0_RX_BUF_DN<11>";
11"P5E_CPU0_P0_RX_BUF_DP<9>";
12"P5E_CPU0_P0_RX_BUF_DP<10>";
13"P5E_CPU0_P0_RX_BUF_DP<12>";
14"P5E_CPU0_P0_RX_BUF_DP<13>";
15"P5E_CPU0_P0_RX_BUF_DP<11>";
16"P5E_CPU0_P0_RX_BUF_DP<4>";
17"P5E_CPU0_P0_RX_BUF_DP<1>";
18"P5E_CPU0_P0_RX_BUF_DP<15>";
19"P5E_CPU0_P0_RX_BUF_DP<8>";
20"P5E_CPU0_P0_RX_BUF_DN<9>";
21"P5E_CPU0_P0_RX_BUF_DP<14>";
22"P5E_CPU0_P0_RX_BUF_DN<8>";
23"P5E_CPU0_P0_RX_BUF_DN<15>";
24"P5E_CPU0_P0_RX_BUF_DN<13>";
25"P5E_CPU0_P0_RX_BUF_DP<0>";
26"P5E_CPU0_P0_RX_BUF_DN<2>";
27"P5E_CPU0_P0_RX_BUF_DP<2>";
28"P5E_CPU0_P0_RX_BUF_DN<3>";
29"P5E_CPU0_P0_RX_BUF_DP<3>";
30"P5E_CPU0_P0_RX_BUF_DN<4>";
31"P5E_CPU0_P0_RX_BUF_DN<5>";
32"P5E_CPU0_P0_RX_BUF_DP<5>";
33"P5E_CPU0_P0_RX_BUF_DN<6>";
34"P5E_CPU0_P0_RX_BUF_DP<6>";
35"P5E_CPU0_P0_RX_BUF_DN<0>";
36"P5E_CPU0_P0_RX_BUF_DP<7>";
%"TAP"
"1","(-7075,3575)","0","standard","I10";
;
CDS_LIB"standard"
BODY_TYPE"PLUMBING"
HDL_TAP"TRUE";
"B \NAC \NWC"4;
"S \NAC"
BN"10"12;
%"TAP"
"1","(-7075,3925)","0","standard","I11";
;
CDS_LIB"standard"
BODY_TYPE"PLUMBING"
HDL_TAP"TRUE";
"B \NAC \NWC"4;
"S \NAC"
BN"11"15;
%"TAP"
"1","(-6875,3825)","0","standard","I12";
;
CDS_LIB"standard"
BODY_TYPE"PLUMBING"
HDL_TAP"TRUE";
"B \NAC \NWC"3;
"S \NAC"
BN"11"10;
%"TAP"
"1","(-7075,4275)","0","standard","I13";
;
CDS_LIB"standard"
BODY_TYPE"PLUMBING"
HDL_TAP"TRUE";
"B \NAC \NWC"4;
"S \NAC"
BN"12"13;
%"TAP"
"1","(-6875,4175)","0","standard","I14";
;
CDS_LIB"standard"
BODY_TYPE"PLUMBING"
HDL_TAP"TRUE";
"B \NAC \NWC"3;
"S \NAC"
BN"12"9;
%"TAP"
"1","(-7075,4625)","0","standard","I15";
;
CDS_LIB"standard"
BODY_TYPE"PLUMBING"
HDL_TAP"TRUE";
"B \NAC \NWC"4;
"S \NAC"
BN"13"14;
%"TAP"
"1","(-7075,4975)","0","standard","I16";
;
CDS_LIB"standard"
BODY_TYPE"PLUMBING"
HDL_TAP"TRUE";
"B \NAC \NWC"4;
"S \NAC"
BN"14"21;
%"TAP"
"1","(-6875,4525)","0","standard","I17";
;
CDS_LIB"standard"
BODY_TYPE"PLUMBING"
HDL_TAP"TRUE";
"B \NAC \NWC"3;
"S \NAC"
BN"13"24;
%"TAP"
"1","(-6875,4875)","0","standard","I18";
;
CDS_LIB"standard"
BODY_TYPE"PLUMBING"
HDL_TAP"TRUE";
"B \NAC \NWC"3;
"S \NAC"
BN"14"8;
%"TAP"
"1","(-7075,5325)","0","standard","I19";
;
CDS_LIB"standard"
BODY_TYPE"PLUMBING"
HDL_TAP"TRUE";
"B \NAC \NWC"4;
"S \NAC"
BN"15"18;
%"TAP"
"1","(-6875,5225)","0","standard","I20";
;
CDS_LIB"standard"
BODY_TYPE"PLUMBING"
HDL_TAP"TRUE";
"B \NAC \NWC"3;
"S \NAC"
BN"15"23;
%"TAP"
"1","(-2625,3600)","0","standard","I23";
;
CDS_LIB"standard"
BODY_TYPE"PLUMBING"
HDL_TAP"TRUE";
"B \NAC \NWC"1;
"S \NAC"
BN"2"27;
%"TAP"
"1","(-2425,3500)","0","standard","I24";
;
CDS_LIB"standard"
BODY_TYPE"PLUMBING"
HDL_TAP"TRUE";
"B \NAC \NWC"2;
"S \NAC"
BN"2"26;
%"TAP"
"1","(-2625,3250)","0","standard","I25";
;
CDS_LIB"standard"
BODY_TYPE"PLUMBING"
HDL_TAP"TRUE";
"B \NAC \NWC"1;
"S \NAC"
BN"1"17;
%"TAP"
"1","(-2425,5250)","0","standard","I28";
;
CDS_LIB"standard"
BODY_TYPE"PLUMBING"
HDL_TAP"TRUE";
"B \NAC \NWC"2;
"S \NAC"
BN"7"5;
%"TAP"
"1","(-2625,5350)","0","standard","I29";
;
CDS_LIB"standard"
BODY_TYPE"PLUMBING"
HDL_TAP"TRUE";
"B \NAC \NWC"1;
"S \NAC"
BN"7"36;
%"PT5161LRS"
"2","(-3650,4100)","0","pure_quanta","I3";
;
LOCATION"U6010"
$SEC"2"
CDS_SEC"2"
MATERIAL"IC"
PART_TYPE"SMLF"
VALUE"PT5161LRS"
CDS_LIB"pure_quanta"
CDS_LMAN_SYM_OUTLINE"-350,1450,300,-1400"
NEEDS_NO_SIZE"TRUE"
PART_NUMBER"AJ051610U03";
"A_PERN15"
$PN"EV2"35;
"A_PERP15"
$PN"EY1"25;
"A_PERN14"
$PN"EL2"6;
"A_PERP14"
$PN"EN1"17;
"A_PERN13"
$PN"ED2"26;
"A_PERP13"
$PN"EF1"27;
"A_PERN12"
$PN"DU2"28;
"A_PERP12"
$PN"DW1"29;
"A_PERN11"
$PN"DK2"30;
"A_PERP11"
$PN"DM1"16;
"A_PERN10"
$PN"DC2"31;
"A_PERP10"
$PN"DE1"32;
"A_PERN9"
$PN"CT2"33;
"A_PERP9"
$PN"CV1"34;
"A_PERN8"
$PN"CJ2"5;
"A_PERP8"
$PN"CL1"36;
%"TAP"
"1","(-2425,4900)","0","standard","I30";
;
CDS_LIB"standard"
BODY_TYPE"PLUMBING"
HDL_TAP"TRUE";
"B \NAC \NWC"2;
"S \NAC"
BN"6"33;
%"TAP"
"1","(-2625,5000)","0","standard","I31";
;
CDS_LIB"standard"
BODY_TYPE"PLUMBING"
HDL_TAP"TRUE";
"B \NAC \NWC"1;
"S \NAC"
BN"6"34;
%"TAP"
"1","(-2625,4650)","0","standard","I32";
;
CDS_LIB"standard"
BODY_TYPE"PLUMBING"
HDL_TAP"TRUE";
"B \NAC \NWC"1;
"S \NAC"
BN"5"32;
%"TAP"
"1","(-2425,4550)","0","standard","I33";
;
CDS_LIB"standard"
BODY_TYPE"PLUMBING"
HDL_TAP"TRUE";
"B \NAC \NWC"2;
"S \NAC"
BN"5"31;
%"TAP"
"1","(-2425,4200)","0","standard","I34";
;
CDS_LIB"standard"
BODY_TYPE"PLUMBING"
HDL_TAP"TRUE";
"B \NAC \NWC"2;
"S \NAC"
BN"4"30;
%"TAP"
"1","(-2625,4300)","0","standard","I35";
;
CDS_LIB"standard"
BODY_TYPE"PLUMBING"
HDL_TAP"TRUE";
"B \NAC \NWC"1;
"S \NAC"
BN"4"16;
%"TAP"
"1","(-2625,3950)","0","standard","I36";
;
CDS_LIB"standard"
BODY_TYPE"PLUMBING"
HDL_TAP"TRUE";
"B \NAC \NWC"1;
"S \NAC"
BN"3"29;
%"TAP"
"1","(-2425,3850)","0","standard","I37";
;
CDS_LIB"standard"
BODY_TYPE"PLUMBING"
HDL_TAP"TRUE";
"B \NAC \NWC"2;
"S \NAC"
BN"3"28;
%"TAP"
"1","(-2425,3150)","0","standard","I38";
;
CDS_LIB"standard"
BODY_TYPE"PLUMBING"
HDL_TAP"TRUE";
"B \NAC \NWC"2;
"S \NAC"
BN"1"6;
%"TAP"
"1","(-2625,2900)","0","standard","I39";
;
CDS_LIB"standard"
BODY_TYPE"PLUMBING"
HDL_TAP"TRUE";
"B \NAC \NWC"1;
"S \NAC"
BN"0"25;
%"PT5161LRS"
"1","(-8100,4075)","0","pure_quanta","I4";
;
LOCATION"U6010"
$SEC"1"
CDS_SEC"1"
VALUE"PT5161LRS"
MATERIAL"IC"
PART_TYPE"SMLF"
NEEDS_NO_SIZE"TRUE"
CDS_LMAN_SYM_OUTLINE"-350,1450,300,-1400"
CDS_LIB"pure_quanta"
PART_NUMBER"AJ051610U03";
"A_PERN7"
$PN"CB2"22;
"A_PERP7"
$PN"CD1"19;
"A_PERN6"
$PN"BR2"20;
"A_PERP6"
$PN"BU1"11;
"A_PERN5"
$PN"BH2"7;
"A_PERP5"
$PN"BK1"12;
"A_PERN4"
$PN"BA2"10;
"A_PERP4"
$PN"BC1"15;
"A_PERN3"
$PN"AP2"9;
"A_PERP3"
$PN"AT1"13;
"A_PERN2"
$PN"AG2"24;
"A_PERP2"
$PN"AJ1"14;
"A_PERN1"
$PN"Y2"8;
"A_PERP1"
$PN"AB1"21;
"A_PERN0"
$PN"N2"23;
"A_PERP0"
$PN"R1"18;
%"TAP"
"1","(-2425,2800)","0","standard","I40";
;
CDS_LIB"standard"
BODY_TYPE"PLUMBING"
HDL_TAP"TRUE";
"B \NAC \NWC"2;
"S \NAC"
BN"0"35;
%"TAP"
"1","(-7075,2875)","0","standard","I5";
;
CDS_LIB"standard"
BODY_TYPE"PLUMBING"
HDL_TAP"TRUE";
"B \NAC \NWC"4;
"S \NAC"
BN"8"19;
%"TAP"
"1","(-6875,2775)","0","standard","I6";
;
CDS_LIB"standard"
BODY_TYPE"PLUMBING"
HDL_TAP"TRUE";
"B \NAC \NWC"3;
"S \NAC"
BN"8"22;
%"TAP"
"1","(-7075,3225)","0","standard","I7";
;
CDS_LIB"standard"
BODY_TYPE"PLUMBING"
HDL_TAP"TRUE";
"B \NAC \NWC"4;
"S \NAC"
BN"9"11;
%"TAP"
"1","(-6875,3125)","0","standard","I8";
;
CDS_LIB"standard"
BODY_TYPE"PLUMBING"
HDL_TAP"TRUE";
"B \NAC \NWC"3;
"S \NAC"
BN"9"20;
%"TAP"
"1","(-6875,3475)","0","standard","I9";
;
CDS_LIB"standard"
BODY_TYPE"PLUMBING"
HDL_TAP"TRUE";
"B \NAC \NWC"3;
"S \NAC"
BN"10"7;
END.
